#ISCELL
  cls sheet_a1 *
  *
#ISCELL
  cls gnd_sg *
  page527_i1
#ISCELL
  cls gnd_sg *
  page527_i100
#CELL
  passive capacitor *
  page527_i103
#CELL
  stdlogic ts3usb3031rmgr_wqfn12 *
  page527_i108
#ISCELL
  cls offpage_bi *
  page527_i11
#ISCELL
  cls offpage_bi *
  page527_i12
#ISCELL
  cls offpage_bi *
  page527_i121
#ISCELL
  cls offpage_bi *
  page527_i122
#CELL
  passive resistor *
  page527_i123
#CELL
  passive resistor *
  page527_i124
#CELL
  passive resistor *
  page527_i126
#ISCELL
  cls gnd_sg *
  page527_i128
#CELL
  passive resistor *
  page527_i13
#ISCELL
  cls offpage_in *
  page527_i137
#ISCELL
  cls gnd_sg *
  page527_i139
#CELL
  passive resistor *
  page527_i14
#ISCELL
  cls gnd_sg *
  page527_i143
#CELL
  passive capacitor *
  page527_i144
#CELL
  stdlogic cl5003148a *
  page527_i146
#CELL
  stdlogic cl5003148a *
  page527_i147
#CELL
  passive resistor *
  page527_i149
#CELL
  passive capacitor *
  page527_i15
#CELL
  passive resistor *
  page527_i155
#CELL
  passive capacitor *
  page527_i16
#ISCELL
  cls offpage_in *
  page527_i161
#ISCELL
  cls offpage_bi *
  page527_i173
#ISCELL
  cls offpage_bi *
  page527_i174
#CELL
  passive resistor *
  page527_i175
#CELL
  passive resistor *
  page527_i176
#ISCELL
  cls offpage_bi *
  page527_i177
#ISCELL
  cls offpage_bi *
  page527_i178
#ISCELL
  cls offpage_bi *
  page527_i179
#ISCELL
  cls offpage_bi *
  page527_i180
#CELL
  passive resistor *
  page527_i187
#ISCELL
  cls vcc *
  page527_i190
#ISCELL
  cls vcc *
  page527_i191
#ISCELL
  cls vcc *
  page527_i192
#CELL
  connector conn_hdr_2x10_m_s_smt *
  page527_i193
#CELL
  connector conn_hdr_1x3_m_s_smt *
  page527_i198
#ISCELL
  cls gnd_sg *
  page527_i199
#CELL
  connector conn_usb_1x5_g2_gh4_f_ra_smt *
  page527_i2
#CELL
  passive resistor *
  page527_i200
#CELL
  passive resistor *
  page527_i201
#CELL
  passive resistor *
  page527_i202
#ISCELL
  cls offpage_out *
  page527_i203
#CELL
  passive resistor *
  page527_i204
#ISCELL
  cls offpage_in *
  page527_i205
#CELL
  passive resistor *
  page527_i206
#ISCELL
  cls offpage_out *
  page527_i207
#CELL
  passive capacitor *
  page527_i208
#CELL
  passive capacitor *
  page527_i209
#ISCELL
  cls vcc *
  page527_i21
#ISCELL
  cls offpage_in *
  page527_i210
#CELL
  passive resistor *
  page527_i211
#ISCELL
  cls vcc *
  page527_i212
#ISCELL
  cls gnd_sg *
  page527_i22
#CELL
  mech nut *
  page527_i220
#CELL
  passive resistor *
  page527_i221
#CELL
  passive resistor *
  page527_i222
#ISCELL
  cls vcc *
  page527_i223
#CELL
  mech nut *
  page527_i224
#CELL
  mech nut *
  page527_i225
#CELL
  mech nut *
  page527_i226
#CELL
  mech nut *
  page527_i227
#CELL
  mech nut *
  page527_i228
#CELL
  mech nut *
  page527_i229
#CELL
  passive resistor *
  page527_i23
#CELL
  mech nut *
  page527_i230
#CELL
  discrete powermos_3p_pch *
  page527_i231
#CELL
  discrete powermos_3p_nch_v1 *
  page527_i232
#CELL
  passive resistor *
  page527_i233
#ISCELL
  cls vcc *
  page527_i234
#ISCELL
  cls vcc *
  page527_i235
#ISCELL
  cls offpage_out *
  page527_i236
#ISCELL
  cls offpage_in *
  page527_i237
#ISCELL
  cls gnd_sg *
  page527_i238
#ISCELL
  cls offpage_out *
  page527_i24
#CELL
  passive resistor *
  page527_i240
#CELL
  passive resistor *
  page527_i241
#ISCELL
  cls offpage_out *
  page527_i242
#ISCELL
  cls offpage_in *
  page527_i243
#CELL
  passive fuse *
  page527_i244
#CELL
  passive resistor *
  page527_i245
#ISCELL
  cls offpage_out *
  page527_i246
#ISCELL
  cls offpage_out *
  page527_i247
#ISCELL
  cls offpage_in *
  page527_i25
#ISCELL
  cls offpage_in *
  page527_i26
#ISCELL
  cls offpage_in *
  page527_i27
#ISCELL
  cls offpage_in *
  page527_i28
#CELL
  passive resistor *
  page527_i29
#ISCELL
  cls gnd_sg *
  page527_i3
#CELL
  passive resistor *
  page527_i30
#CELL
  passive resistor *
  page527_i31
#CELL
  passive resistor *
  page527_i32
#CELL
  passive resistor *
  page527_i33
#CELL
  passive resistor *
  page527_i34
#ISCELL
  cls gnd_sg *
  page527_i37
#CELL
  other cl1001485a *
  page527_i4
#ISCELL
  cls gnd_sg *
  page527_i45
#ISCELL
  cls vcc *
  page527_i46
#CELL
  passive capacitor *
  page527_i47
#CELL
  passive capacitor *
  page527_i48
#ISCELL
  cls vcc *
  page527_i49
#ISCELL
  cls gnd_sg *
  page527_i50
#CELL
  passive capacitor *
  page527_i51
#CELL
  passive resistor *
  page527_i52
#CELL
  passive resistor *
  page527_i53
#CELL
  passive resistor *
  page527_i54
#CELL
  passive resistor *
  page527_i55
#CELL
  passive capacitor *
  page527_i56
#CELL
  passive capacitor *
  page527_i57
#ISCELL
  cls offpage_out *
  page527_i6
#ISCELL
  cls offpage_in *
  page527_i62
#ISCELL
  cls offpage_out *
  page527_i63
#ISCELL
  cls offpage_out *
  page527_i64
#ISCELL
  cls offpage_out *
  page527_i65
#CELL
  passive capacitor *
  page527_i66
#ISCELL
  cls offpage_out *
  page527_i7
#ISCELL
  cls gnd_sg *
  page527_i71
#ISCELL
  cls gnd_sg *
  page527_i73
#CELL
  passive capacitor *
  page527_i74
#CELL
  passive capacitor *
  page527_i77
#CELL
  stdlogic tps2051bdbvt_sot23_5 *
  page527_i78
#CELL
  stdlogic tps2051bdbvt_sot23_5 *
  page527_i79
#CELL
  passive resistor *
  page527_i83
#CELL
  passive capacitor *
  page527_i85
#ISCELL
  cls vcc *
  page527_i88
#ISCELL
  cls vcc *
  page527_i89
#CELL
  passive ferritebead *
  page527_i91
#ISCELL
  cls vcc *
  page527_i92
#CELL
  passive capacitor *
  page527_i93
#ISCELL
  cls gnd_sg *
  page527_i96
